# BASEBOARD_FAB2 (Tioga Pass) — schematic netlist excerpt (pin names and nets, part order shuffled) for the footprints in the layout excerpt that follows; sources: Cadence DE-HDL packaged netlist, KiCad conversion of Wiwynn_Tioga_Pass_MB.brd

L7F2  IND-100NH-35-GP  pkg DISCRET-G8  page 217 : S = P12V_STBY ; F = VR_FET_SW_P12V_STBY_PVDDQ_ABC
R25W80  RES  10.0K 1% CHIP  pkg 0402  page 147 : A = P3V3_STBY ; B = RMII_SPRNGVLLE_BMC_PCH_RXD1
C1F6  CAP  0.22UF 16V 10% X7R  pkg 0402  page 181 : A = P3E_CPU1_PE3_MP_C_TXP<5> ; B = P3E_CPU1_PE3_MP_TXP<5>

(kicad_pcb
	(version 20260206)
	(generator "pcbnew")
	(generator_version "10.0")
	(general
		(thickness 1.6)
		(legacy_teardrops no)
	)
	(paper "A4")
	(title_block
		(title "Wiwynn_Tioga_Pass_MB.brd")
		(comment 1 "Tioga Pass / footprints 742-744 of 4770")
	)
	(layers
		(0 "F.Cu" signal "TOP")
		(4 "In1.Cu" signal "L2GND")
		(6 "In2.Cu" signal "L3")
		(8 "In3.Cu" signal "L4GND")
		(10 "In4.Cu" signal "L5")
		(12 "In5.Cu" signal "L6GND")
		(14 "In6.Cu" signal "L7VCC")
		(16 "In7.Cu" signal "L8VCC")
		(18 "In8.Cu" signal "L9GND")
		(20 "In9.Cu" signal "L10")
		(22 "In10.Cu" signal "L11GND")
		(24 "In11.Cu" signal "L12")
		(26 "In12.Cu" signal "L13GND")
		(2 "B.Cu" signal "BOTTOM")
		(9 "F.Adhes" user "F.Adhesive")
		(11 "B.Adhes" user "B.Adhesive")
		(13 "F.Paste" user "Package Geometry/Pastemask Top")
		(15 "B.Paste" user "Package Geometry/Pastemask Bottom")
		(5 "F.SilkS" user "Ref Des/Silkscreen Top")
		(7 "B.SilkS" user "Ref Des/Silkscreen Bottom")
		(1 "F.Mask" user "Board Geometry/Soldermask Top")
		(3 "B.Mask" user "Board Geometry/Soldermask Bottom")
		(17 "Dwgs.User" user "User.Drawings")
		(19 "Cmts.User" user "User.Comments")
		(21 "Eco1.User" user "User.Eco1")
		(23 "Eco2.User" user "User.Eco2")
		(25 "Edge.Cuts" user "Board Geometry/Outline")
		(27 "Margin" user)
		(31 "F.CrtYd" user "Package Geometry/Place Bound Top")
		(29 "B.CrtYd" user "Package Geometry/Place Bound Bottom")
		(35 "F.Fab" user "Ref Des/Assembly Top")
		(33 "B.Fab" user "Ref Des/Assembly Bottom")
	)
	(footprint ""
		(layer "F.Cu")
		(at 355.666548 -22.035516 -90)
		(property "Reference" "L7F2"
			(at 0 0 270)
			(layer "F.SilkS")
			(hide yes)
			(effects
				(font
					(size 1.27 1.27)
				)
			)
		)
		(property "Value" "*"
			(at -3.5941 0.3429 270)
			(unlocked yes)
			(layer "F.Fab")
			(hide yes)
			(effects
				(font
					(size 1.27 1.016)
					(thickness 0.1524)
				)
			)
		)
		(property "Device Type" "IND-100NH-35-GP_DISCRET-G8-INDA"
			(at -3.5941 -1.1811 270)
			(unlocked yes)
			(layer "F.Fab")
			(hide yes)
			(effects
				(font
					(size 1.27 1.016)
					(thickness 0.1524)
				)
			)
		)
		(duplicate_pad_numbers_are_jumpers no)
		(fp_line
			(start -2.2479 2.794)
			(end -2.2479 -2.794)
			(stroke
				(width 0.1524)
				(type default)
			)
			(layer "F.SilkS")
		)
		(fp_line
			(start 2.2479 2.794)
			(end -2.2479 2.794)
			(stroke
				(width 0.1524)
				(type default)
			)
			(layer "F.SilkS")
		)
		(fp_line
			(start -2.2479 -2.794)
			(end 2.2479 -2.794)
			(stroke
				(width 0.1524)
				(type default)
			)
			(layer "F.SilkS")
		)
		(fp_line
			(start 2.2479 -2.794)
			(end 2.2479 2.794)
			(stroke
				(width 0.1524)
				(type default)
			)
			(layer "F.SilkS")
		)
		(fp_rect
			(start -1.9939 1.9939)
			(end 1.9939 -1.9939)
			(stroke
				(width 0)
				(type default)
			)
			(fill no)
			(layer "F.CrtYd")
		)
		(fp_poly
			(pts
				(xy -2.5019 2.8702) (xy -2.5019 1.9939) (xy 1.9939 1.9939) (xy 1.9939 -1.9939) (xy -1.9939 -1.9939)
				(xy -1.9939 1.9812) (xy -2.5019 1.9812) (xy -2.5019 -2.8702) (xy 2.5019 -2.8702) (xy 2.5019 2.8702)
			)
			(stroke
				(width 0)
				(type default)
			)
			(fill no)
			(layer "F.CrtYd")
		)
		(fp_rect
			(start -2.5019 2.8702)
			(end 2.5019 -2.8702)
			(stroke
				(width 0)
				(type default)
			)
			(fill no)
			(layer "F.Fab")
		)
		(pad "1" smd rect
			(at 0 -1.745996 270)
			(size 1.5494 1.6002)
			(layers "F.Cu" "F.Mask" "F.Paste")
			(net "P12V_STBY")
		)
		(pad "2" smd rect
			(at 0 1.745996 270)
			(size 1.5494 1.6002)
			(layers "F.Cu" "F.Mask" "F.Paste")
			(net "VR_FET_SW_P12V_STBY_PVDDQ_ABC")
		)
	)
	(footprint ""
		(layer "F.Cu")
		(at 13.8938 -33.02 90)
		(property "Reference" "C1F6"
			(at 0 0 90)
			(layer "F.SilkS")
			(hide yes)
			(effects
				(font
					(size 1.27 1.27)
				)
			)
		)
		(property "Value" ""
			(at 0 0 90)
			(layer "F.Fab")
			(effects
				(font
					(size 1.27 1.27)
				)
			)
		)
		(duplicate_pad_numbers_are_jumpers no)
		(fp_rect
			(start -0.3048 -0.1016)
			(end 0.3048 0.9906)
			(stroke
				(width 0)
				(type default)
			)
			(fill no)
			(layer "F.CrtYd")
		)
		(fp_line
			(start 0.3048 -0.1016)
			(end -0.3048 -0.1016)
			(stroke
				(width 0.1)
				(type default)
			)
			(layer "F.Fab")
		)
		(fp_line
			(start -0.3048 -0.1016)
			(end -0.3048 0.9906)
			(stroke
				(width 0.1)
				(type default)
			)
			(layer "F.Fab")
		)
		(fp_line
			(start 0.3048 0.9906)
			(end 0.3048 -0.1016)
			(stroke
				(width 0.1)
				(type default)
			)
			(layer "F.Fab")
		)
		(fp_line
			(start -0.3048 0.9906)
			(end 0.3048 0.9906)
			(stroke
				(width 0.1)
				(type default)
			)
			(layer "F.Fab")
		)
		(pad "1" smd rect
			(at 0 0 90)
			(size 0.508 0.508)
			(layers "F.Cu" "F.Mask" "F.Paste")
			(net "P3E_CPU1_PE3_MP_C_TXP<5>")
		)
		(pad "2" smd rect
			(at 0 0.889 90)
			(size 0.508 0.508)
			(layers "F.Cu" "F.Mask" "F.Paste")
			(net "P3E_CPU1_PE3_MP_TXP<5>")
		)
		(zone
			(layer "F.Cu")
			(hatch none 0.5)
			(connect_pads
				(clearance 0)
			)
			(min_thickness 0.25)
			(keepout
				(tracks not_allowed)
				(vias allowed)
				(pads allowed)
				(copperpour not_allowed)
				(footprints allowed)
			)
			(placement
				(enabled no)
				(sheetname "")
			)
			(fill
				(thermal_gap 0.5)
				(thermal_bridge_width 0.5)
				(island_removal_mode 0)
			)
			(polygon
				(pts
					(xy 14.1478 -32.766) (xy 14.5288 -32.766) (xy 14.5288 -33.274) (xy 14.1478 -33.274)
				)
			)
		)
		(zone
			(layer "F.Cu")
			(hatch none 0.5)
			(connect_pads
				(clearance 0)
			)
			(min_thickness 0.25)
			(keepout
				(tracks allowed)
				(vias not_allowed)
				(pads allowed)
				(copperpour not_allowed)
				(footprints allowed)
			)
			(placement
				(enabled no)
				(sheetname "")
			)
			(fill
				(thermal_gap 0.5)
				(thermal_bridge_width 0.5)
				(island_removal_mode 0)
			)
			(polygon
				(pts
					(xy 14.1478 -32.766) (xy 14.5288 -32.766) (xy 14.5288 -33.274) (xy 14.1478 -33.274)
				)
			)
		)
	)
	(footprint ""
		(layer "F.Cu")
		(at 407.7335 -22.987 90)
		(property "Reference" "R25W80"
			(at -0.8382 -0.67818 90)
			(unlocked yes)
			(layer "F.SilkS")
			(effects
				(font
					(size 0.4064 0.254)
					(thickness 0.1524)
				)
				(justify left)
			)
		)
		(property "Value" ""
			(at 0 0 90)
			(layer "F.Fab")
			(effects
				(font
					(size 1.27 1.27)
				)
			)
		)
		(duplicate_pad_numbers_are_jumpers no)
		(fp_poly
			(pts
				(xy -0.2794 -0.1016) (xy 0.2794 -0.1016) (xy 0.2794 0.9906) (xy -0.2794 0.9906)
			)
			(stroke
				(width 0)
				(type default)
			)
			(fill no)
			(layer "F.CrtYd")
		)
		(fp_line
			(start 0.2794 -0.1016)
			(end -0.2794 -0.1016)
			(stroke
				(width 0.1)
				(type default)
			)
			(layer "F.Fab")
		)
		(fp_line
			(start -0.2794 -0.1016)
			(end -0.2794 0.9906)
			(stroke
				(width 0.1)
				(type default)
			)
			(layer "F.Fab")
		)
		(fp_line
			(start 0.2794 0.9906)
			(end 0.2794 -0.1016)
			(stroke
				(width 0.1)
				(type default)
			)
			(layer "F.Fab")
		)
		(fp_line
			(start -0.2794 0.9906)
			(end 0.2794 0.9906)
			(stroke
				(width 0.1)
				(type default)
			)
			(layer "F.Fab")
		)
		(pad "1" smd rect
			(at 0 0 90)
			(size 0.508 0.508)
			(layers "F.Cu" "F.Mask" "F.Paste")
			(net "P3V3_STBY")
		)
		(pad "2" smd rect
			(at 0 0.889 90)
			(size 0.508 0.508)
			(layers "F.Cu" "F.Mask" "F.Paste")
			(net "RMII_SPRNGVLLE_BMC_PCH_RXD1")
		)
		(zone
			(layer "F.Cu")
			(hatch none 0.5)
			(connect_pads
				(clearance 0)
			)
			(min_thickness 0.25)
			(keepout
				(tracks allowed)
				(vias not_allowed)
				(pads allowed)
				(copperpour not_allowed)
				(footprints allowed)
			)
			(placement
				(enabled no)
				(sheetname "")
			)
			(fill
				(thermal_gap 0.5)
				(thermal_bridge_width 0.5)
				(island_removal_mode 0)
			)
			(polygon
				(pts
					(xy 407.9875 -22.733) (xy 407.9875 -23.241) (xy 408.3685 -23.241) (xy 408.3685 -22.733)
				)
			)
		)
		(zone
			(layer "F.Cu")
			(hatch none 0.5)
			(connect_pads
				(clearance 0)
			)
			(min_thickness 0.25)
			(keepout
				(tracks not_allowed)
				(vias allowed)
				(pads allowed)
				(copperpour not_allowed)
				(footprints allowed)
			)
			(placement
				(enabled no)
				(sheetname "")
			)
			(fill
				(thermal_gap 0.5)
				(thermal_bridge_width 0.5)
				(island_removal_mode 0)
			)
			(polygon
				(pts
					(xy 408.3685 -22.733) (xy 408.3685 -23.241) (xy 407.9875 -23.241) (xy 407.9875 -22.733)
				)
			)
		)
	)
)
